# BASEBOARD_FAB2 (Tioga Pass) — schematic netlist excerpt (pin names and nets, part order shuffled) for the footprints in the layout excerpt that follows; sources: Cadence DE-HDL packaged netlist, KiCad conversion of Wiwynn_Tioga_Pass_MB.brd

R9T1  RES  0.0 5% CHIP  pkg 0402  page 181 : A = FAN_PWM_OUT_SYS0_R ; B = FAN_PWM_OUT_SYS0_R1
R1L30  RES  10.0 1% CHIP  pkg 0402  page 155 : A = LED_POSTCODE_1 ; B = LED_POSTCODE_1_R
C3M43  CAP_A  1.0UF 6.3V 10% X6S  pkg 0402V  page 131 : A = P1V05_PCH_STBY ; B = GND

(kicad_pcb
	(version 20260206)
	(generator "pcbnew")
	(generator_version "10.0")
	(general
		(thickness 1.6)
		(legacy_teardrops no)
	)
	(paper "A4")
	(title_block
		(title "Wiwynn_Tioga_Pass_MB.brd")
		(comment 1 "Tioga Pass / footprints 4044-4046 of 4770")
	)
	(layers
		(0 "F.Cu" signal "TOP")
		(4 "In1.Cu" signal "L2GND")
		(6 "In2.Cu" signal "L3")
		(8 "In3.Cu" signal "L4GND")
		(10 "In4.Cu" signal "L5")
		(12 "In5.Cu" signal "L6GND")
		(14 "In6.Cu" signal "L7VCC")
		(16 "In7.Cu" signal "L8VCC")
		(18 "In8.Cu" signal "L9GND")
		(20 "In9.Cu" signal "L10")
		(22 "In10.Cu" signal "L11GND")
		(24 "In11.Cu" signal "L12")
		(26 "In12.Cu" signal "L13GND")
		(2 "B.Cu" signal "BOTTOM")
		(9 "F.Adhes" user "F.Adhesive")
		(11 "B.Adhes" user "B.Adhesive")
		(13 "F.Paste" user "Package Geometry/Pastemask Top")
		(15 "B.Paste" user "Package Geometry/Pastemask Bottom")
		(5 "F.SilkS" user "Ref Des/Silkscreen Top")
		(7 "B.SilkS" user "Ref Des/Silkscreen Bottom")
		(1 "F.Mask" user "Board Geometry/Soldermask Top")
		(3 "B.Mask" user "Board Geometry/Soldermask Bottom")
		(17 "Dwgs.User" user "User.Drawings")
		(19 "Cmts.User" user "User.Comments")
		(21 "Eco1.User" user "User.Eco1")
		(23 "Eco2.User" user "User.Eco2")
		(25 "Edge.Cuts" user "Board Geometry/Outline")
		(27 "Margin" user)
		(31 "F.CrtYd" user "Package Geometry/Place Bound Top")
		(29 "B.CrtYd" user "Package Geometry/Place Bound Bottom")
		(35 "F.Fab" user "Ref Des/Assembly Top")
		(33 "B.Fab" user "Ref Des/Assembly Bottom")
	)
	(footprint ""
		(layer "B.Cu")
		(at 494.4872 -137.7696 180)
		(property "Reference" "R1L30"
			(at 0 0 0)
			(layer "B.SilkS")
			(hide yes)
			(effects
				(font
					(size 1.27 1.27)
				)
				(justify mirror)
			)
		)
		(property "Value" ""
			(at 0 0 0)
			(layer "B.Fab")
			(effects
				(font
					(size 1.27 1.27)
				)
				(justify mirror)
			)
		)
		(duplicate_pad_numbers_are_jumpers no)
		(fp_poly
			(pts
				(xy 0.2794 -0.1016) (xy -0.2794 -0.1016) (xy -0.2794 0.9906) (xy 0.2794 0.9906)
			)
			(stroke
				(width 0)
				(type default)
			)
			(fill no)
			(layer "B.CrtYd")
		)
		(fp_line
			(start 0.2794 0.9906)
			(end -0.2794 0.9906)
			(stroke
				(width 0.1)
				(type default)
			)
			(layer "B.Fab")
		)
		(fp_line
			(start 0.2794 -0.1016)
			(end 0.2794 0.9906)
			(stroke
				(width 0.1)
				(type default)
			)
			(layer "B.Fab")
		)
		(fp_line
			(start -0.2794 0.9906)
			(end -0.2794 -0.1016)
			(stroke
				(width 0.1)
				(type default)
			)
			(layer "B.Fab")
		)
		(fp_line
			(start -0.2794 -0.1016)
			(end 0.2794 -0.1016)
			(stroke
				(width 0.1)
				(type default)
			)
			(layer "B.Fab")
		)
		(pad "1" smd rect
			(at 0 0)
			(size 0.508 0.508)
			(layers "B.Cu" "B.Mask" "B.Paste")
			(net "LED_POSTCODE_1")
		)
		(pad "2" smd rect
			(at 0 0.889)
			(size 0.508 0.508)
			(layers "B.Cu" "B.Mask" "B.Paste")
			(net "LED_POSTCODE_1_R")
		)
		(zone
			(layer "B.Cu")
			(hatch none 0.5)
			(connect_pads
				(clearance 0)
			)
			(min_thickness 0.25)
			(keepout
				(tracks not_allowed)
				(vias allowed)
				(pads allowed)
				(copperpour not_allowed)
				(footprints allowed)
			)
			(placement
				(enabled no)
				(sheetname "")
			)
			(fill
				(thermal_gap 0.5)
				(thermal_bridge_width 0.5)
				(island_removal_mode 0)
			)
			(polygon
				(pts
					(xy 494.2332 -138.4046) (xy 494.7412 -138.4046) (xy 494.7412 -138.0236) (xy 494.2332 -138.0236)
				)
			)
		)
		(zone
			(layer "B.Cu")
			(hatch none 0.5)
			(connect_pads
				(clearance 0)
			)
			(min_thickness 0.25)
			(keepout
				(tracks allowed)
				(vias not_allowed)
				(pads allowed)
				(copperpour not_allowed)
				(footprints allowed)
			)
			(placement
				(enabled no)
				(sheetname "")
			)
			(fill
				(thermal_gap 0.5)
				(thermal_bridge_width 0.5)
				(island_removal_mode 0)
			)
			(polygon
				(pts
					(xy 494.2332 -138.0236) (xy 494.7412 -138.0236) (xy 494.7412 -138.4046) (xy 494.2332 -138.4046)
				)
			)
		)
	)
	(footprint ""
		(layer "B.Cu")
		(at 13.97 -40.513 -90)
		(property "Reference" "R9T1"
			(at 0 0 90)
			(layer "B.SilkS")
			(hide yes)
			(effects
				(font
					(size 1.27 1.27)
				)
				(justify mirror)
			)
		)
		(property "Value" ""
			(at 0 0 90)
			(layer "B.Fab")
			(effects
				(font
					(size 1.27 1.27)
				)
				(justify mirror)
			)
		)
		(duplicate_pad_numbers_are_jumpers no)
		(fp_poly
			(pts
				(xy 0.2794 -0.1016) (xy -0.2794 -0.1016) (xy -0.2794 0.9906) (xy 0.2794 0.9906)
			)
			(stroke
				(width 0)
				(type default)
			)
			(fill no)
			(layer "B.CrtYd")
		)
		(fp_line
			(start -0.2794 0.9906)
			(end -0.2794 -0.1016)
			(stroke
				(width 0.1)
				(type default)
			)
			(layer "B.Fab")
		)
		(fp_line
			(start 0.2794 0.9906)
			(end -0.2794 0.9906)
			(stroke
				(width 0.1)
				(type default)
			)
			(layer "B.Fab")
		)
		(fp_line
			(start -0.2794 -0.1016)
			(end 0.2794 -0.1016)
			(stroke
				(width 0.1)
				(type default)
			)
			(layer "B.Fab")
		)
		(fp_line
			(start 0.2794 -0.1016)
			(end 0.2794 0.9906)
			(stroke
				(width 0.1)
				(type default)
			)
			(layer "B.Fab")
		)
		(pad "1" smd rect
			(at 0 0 90)
			(size 0.508 0.508)
			(layers "B.Cu" "B.Mask" "B.Paste")
			(net "FAN_PWM_OUT_SYS0_R")
		)
		(pad "2" smd rect
			(at 0 0.889 90)
			(size 0.508 0.508)
			(layers "B.Cu" "B.Mask" "B.Paste")
			(net "FAN_PWM_OUT_SYS0_R1")
		)
		(zone
			(layer "B.Cu")
			(hatch none 0.5)
			(connect_pads
				(clearance 0)
			)
			(min_thickness 0.25)
			(keepout
				(tracks not_allowed)
				(vias allowed)
				(pads allowed)
				(copperpour not_allowed)
				(footprints allowed)
			)
			(placement
				(enabled no)
				(sheetname "")
			)
			(fill
				(thermal_gap 0.5)
				(thermal_bridge_width 0.5)
				(island_removal_mode 0)
			)
			(polygon
				(pts
					(xy 13.335 -40.259) (xy 13.335 -40.767) (xy 13.716 -40.767) (xy 13.716 -40.259)
				)
			)
		)
		(zone
			(layer "B.Cu")
			(hatch none 0.5)
			(connect_pads
				(clearance 0)
			)
			(min_thickness 0.25)
			(keepout
				(tracks allowed)
				(vias not_allowed)
				(pads allowed)
				(copperpour not_allowed)
				(footprints allowed)
			)
			(placement
				(enabled no)
				(sheetname "")
			)
			(fill
				(thermal_gap 0.5)
				(thermal_bridge_width 0.5)
				(island_removal_mode 0)
			)
			(polygon
				(pts
					(xy 13.716 -40.259) (xy 13.716 -40.767) (xy 13.335 -40.767) (xy 13.335 -40.259)
				)
			)
		)
	)
	(footprint ""
		(layer "B.Cu")
		(at 386.93725 -113.45545)
		(property "Reference" "C3M43"
			(at 0 0 0)
			(layer "B.SilkS")
			(hide yes)
			(effects
				(font
					(size 1.27 1.27)
				)
				(justify mirror)
			)
		)
		(property "Value" ""
			(at 0 0 0)
			(layer "B.Fab")
			(effects
				(font
					(size 1.27 1.27)
				)
				(justify mirror)
			)
		)
		(duplicate_pad_numbers_are_jumpers no)
		(fp_rect
			(start 0.2794 0.9144)
			(end -0.2794 -0.1143)
			(stroke
				(width 0)
				(type default)
			)
			(fill no)
			(layer "B.CrtYd")
		)
		(fp_line
			(start -0.2794 -0.1143)
			(end -0.2794 0.9144)
			(stroke
				(width 0.1)
				(type default)
			)
			(layer "B.Fab")
		)
		(fp_line
			(start -0.2794 0.9144)
			(end 0.2794 0.9144)
			(stroke
				(width 0.1)
				(type default)
			)
			(layer "B.Fab")
		)
		(fp_line
			(start 0.2794 -0.1143)
			(end -0.2794 -0.1143)
			(stroke
				(width 0.1)
				(type default)
			)
			(layer "B.Fab")
		)
		(fp_line
			(start 0.2794 0.9144)
			(end 0.2794 -0.1143)
			(stroke
				(width 0.1)
				(type default)
			)
			(layer "B.Fab")
		)
		(pad "1" smd custom
			(at 0 0 270)
			(size 0.10414 0.10414)
			(layers "B.Cu" "B.Mask" "B.Paste")
			(net "P1V05_PCH_STBY")
			(options
				(clearance outline)
				(anchor circle)
			)
			(primitives
				(gr_poly
					(pts
						(xy -0.20828 -0.08636) (xy -0.20828 0.08636) (xy -0.08636 0.20828) (xy 0.086614 0.20828) (xy 0.20828 0.086614)
						(xy 0.20828 -0.08636) (xy 0.08636 -0.20828) (xy -0.08636 -0.20828)
					)
					(width 0)
					(fill yes)
				)
			)
		)
		(pad "2" smd custom
			(at 0 0.8001 270)
			(size 0.10414 0.10414)
			(layers "B.Cu" "B.Mask" "B.Paste")
			(net "GND")
			(options
				(clearance outline)
				(anchor circle)
			)
			(primitives
				(gr_poly
					(pts
						(xy -0.20828 -0.08636) (xy -0.20828 0.08636) (xy -0.08636 0.20828) (xy 0.086614 0.20828) (xy 0.20828 0.086614)
						(xy 0.20828 -0.08636) (xy 0.08636 -0.20828) (xy -0.08636 -0.20828)
					)
					(width 0)
					(fill yes)
				)
			)
		)
		(zone
			(layer "B.Cu")
			(hatch none 0.5)
			(connect_pads
				(clearance 0)
			)
			(min_thickness 0.25)
			(keepout
				(tracks allowed)
				(vias not_allowed)
				(pads allowed)
				(copperpour not_allowed)
				(footprints allowed)
			)
			(placement
				(enabled no)
				(sheetname "")
			)
			(fill
				(thermal_gap 0.5)
				(thermal_bridge_width 0.5)
				(island_removal_mode 0)
			)
			(polygon
				(pts
					(xy 387.02488 -113.2459) (xy 387.02488 -112.8649) (xy 386.84962 -112.8649) (xy 386.849366 -113.2459)
				)
			)
		)
		(zone
			(layer "B.Cu")
			(hatch none 0.5)
			(connect_pads
				(clearance 0)
			)
			(min_thickness 0.25)
			(keepout
				(tracks not_allowed)
				(vias allowed)
				(pads allowed)
				(copperpour not_allowed)
				(footprints allowed)
			)
			(placement
				(enabled no)
				(sheetname "")
			)
			(fill
				(thermal_gap 0.5)
				(thermal_bridge_width 0.5)
				(island_removal_mode 0)
			)
			(polygon
				(pts
					(xy 387.02488 -113.2459) (xy 387.02488 -112.8649) (xy 386.84962 -112.8649) (xy 386.849366 -113.2459)
				)
			)
		)
	)
)
